(kicad_pcb
	(version 20240108)
	(generator "pcbnew")
	(generator_version "8.0")
	(general
		(thickness 1.62)
		(legacy_teardrops no)
	)
	(paper "A4")
	(title_block
		(title "Jetson Orin Baseboard")
		(date "2025-03-12")
		(rev "1.3.4")
		(company "Antmicro Ltd")
		(comment 1 "www.antmicro.com")
		(comment 9 "footprints 449-453 of 677")
	)
	(layers
		(0 "F.Cu" signal)
		(1 "In1.Cu" signal)
		(2 "In2.Cu" signal)
		(3 "In3.Cu" signal)
		(4 "In4.Cu" jumper)
		(5 "In5.Cu" signal)
		(6 "In6.Cu" signal)
		(31 "B.Cu" signal)
		(32 "B.Adhes" user "B.Adhesive")
		(33 "F.Adhes" user "F.Adhesive")
		(34 "B.Paste" user)
		(35 "F.Paste" user)
		(36 "B.SilkS" user "B.Silkscreen")
		(37 "F.SilkS" user "F.Silkscreen")
		(38 "B.Mask" user)
		(39 "F.Mask" user)
		(40 "Dwgs.User" user "User.Drawings")
		(41 "Cmts.User" user "User.Comments")
		(42 "Eco1.User" user "User.Eco1")
		(43 "Eco2.User" user "User.Eco2")
		(44 "Edge.Cuts" user)
		(45 "Margin" user)
		(46 "B.CrtYd" user "B.Courtyard")
		(47 "F.CrtYd" user "F.Courtyard")
		(48 "B.Fab" user)
		(49 "F.Fab" user)
	)
	(footprint "antmicro-footprints:C_0402_1005Metric"
		(layer "B.Cu")
		(at 126.735 86.75)
		(descr "Capacitor SMD 0402")
		(tags "capacitor SMD 0402")
		(property "Reference" "C14"
			(at 2.965 0.4 180)
			(layer "B.SilkS")
			(effects
				(font
					(size 0.7 0.7)
					(thickness 0.15)
				)
				(justify left bottom mirror)
			)
		)
		(property "Value" "C_220n_0402"
			(at 0 -1.4 180)
			(layer "B.Fab")
			(effects
				(font
					(size 0.7 0.7)
					(thickness 0.15)
				)
				(justify left bottom mirror)
			)
		)
		(property "Footprint" "antmicro-footprints:C_0402_1005Metric"
			(at 0 0 0)
			(layer "F.Fab")
			(hide yes)
			(effects
				(font
					(size 1.27 1.27)
					(thickness 0.15)
				)
			)
		)
		(property "Datasheet" "https://www.yageo.com/en/Chart/Download/pdf/CC0402KRX5R6BB224"
			(at 0 0 0)
			(layer "F.Fab")
			(hide yes)
			(effects
				(font
					(size 1.27 1.27)
					(thickness 0.15)
				)
			)
		)
		(property "Author" "Antmicro"
			(at 0 0 0)
			(layer "B.Fab")
			(hide yes)
			(effects
				(font
					(size 1 1)
					(thickness 0.15)
				)
				(justify mirror)
			)
		)
		(property "Dielectric" ""
			(at 0 0 0)
			(layer "B.Fab")
			(hide yes)
			(effects
				(font
					(size 1 1)
					(thickness 0.15)
				)
				(justify mirror)
			)
		)
		(property "License" "Apache-2.0"
			(at 0 0 0)
			(layer "B.Fab")
			(hide yes)
			(effects
				(font
					(size 1 1)
					(thickness 0.15)
				)
				(justify mirror)
			)
		)
		(property "MPN" "CC0402KRX5R6BB224"
			(at 0 0 0)
			(layer "B.Fab")
			(hide yes)
			(effects
				(font
					(size 1 1)
					(thickness 0.15)
				)
				(justify mirror)
			)
		)
		(property "Manufacturer" "YAGEO"
			(at 0 0 0)
			(layer "B.Fab")
			(hide yes)
			(effects
				(font
					(size 1 1)
					(thickness 0.15)
				)
				(justify mirror)
			)
		)
		(property "Val" "220n"
			(at 0 0 0)
			(layer "B.Fab")
			(hide yes)
			(effects
				(font
					(size 1 1)
					(thickness 0.15)
				)
				(justify mirror)
			)
		)
		(property "Voltage" ""
			(at 0 0 0)
			(layer "B.Fab")
			(hide yes)
			(effects
				(font
					(size 1 1)
					(thickness 0.15)
				)
				(justify mirror)
			)
		)
		(sheetname "M.2")
		(sheetfile "m-2.kicad_sch")
		(attr smd)
		(fp_rect
			(start -0.925 0.47)
			(end 0.925 -0.47)
			(stroke
				(width 0.05)
				(type default)
			)
			(fill none)
			(layer "B.CrtYd")
		)
		(fp_line
			(start -0.494 -0.248)
			(end 0.504 -0.248)
			(stroke
				(width 0.15)
				(type solid)
			)
			(layer "B.Fab")
		)
		(fp_line
			(start -0.494 0.25)
			(end -0.494 -0.248)
			(stroke
				(width 0.15)
				(type solid)
			)
			(layer "B.Fab")
		)
		(fp_line
			(start 0.504 -0.248)
			(end 0.504 0.25)
			(stroke
				(width 0.15)
				(type solid)
			)
			(layer "B.Fab")
		)
		(fp_line
			(start 0.504 0.25)
			(end -0.494 0.25)
			(stroke
				(width 0.15)
				(type solid)
			)
			(layer "B.Fab")
		)
		(fp_text user "Author: Antmicro"
			(at -0.932 -4.17 180)
			(layer "B.Fab")
			(hide yes)
			(effects
				(font
					(size 0.7 0.7)
					(thickness 0.15)
				)
				(justify left bottom mirror)
			)
		)
		(fp_text user "License: Apache-2.0"
			(at -0.932 -5.17 180)
			(layer "B.Fab")
			(hide yes)
			(effects
				(font
					(size 0.7 0.7)
					(thickness 0.15)
				)
				(justify left bottom mirror)
			)
		)
		(fp_text user "${REFERENCE}"
			(at -0.932 -3.168 180)
			(layer "B.Fab")
			(hide yes)
			(effects
				(font
					(size 0.7 0.7)
					(thickness 0.15)
				)
				(justify left bottom mirror)
			)
		)
		(pad "1" smd roundrect
			(at -0.48 0)
			(size 0.59 0.64)
			(layers "B.Cu" "B.Paste" "B.Mask")
			(roundrect_rratio 0.25)
			(net 90 "/M.2/C_PCIE0_TX1_P")
			(pintype "passive")
		)
		(pad "2" smd roundrect
			(at 0.48 0)
			(size 0.59 0.64)
			(layers "B.Cu" "B.Paste" "B.Mask")
			(roundrect_rratio 0.25)
			(net 444 "PCIE0_TX1_P")
			(pintype "passive")
		)
	)
	(footprint "antmicro-footprints:R_0402_1005Metric"
		(layer "B.Cu")
		(at 77.6 108.4 180)
		(descr "Resistor SMD 0402")
		(tags "resistor SMD 0402")
		(property "Reference" "R94"
			(at -3.14 -2.38 0)
			(layer "B.SilkS")
			(effects
				(font
					(size 0.7 0.7)
					(thickness 0.15)
				)
				(justify left bottom mirror)
			)
		)
		(property "Value" "R_1k_0402"
			(at 0 -1.4 0)
			(layer "B.Fab")
			(effects
				(font
					(size 0.7 0.7)
					(thickness 0.15)
				)
				(justify left bottom mirror)
			)
		)
		(property "Footprint" "antmicro-footprints:R_0402_1005Metric"
			(at 0 0 180)
			(layer "F.Fab")
			(hide yes)
			(effects
				(font
					(size 1.27 1.27)
					(thickness 0.15)
				)
			)
		)
		(property "Datasheet" "https://www.bourns.com/docs/product-datasheets/cr.pdf"
			(at 0 0 180)
			(layer "F.Fab")
			(hide yes)
			(effects
				(font
					(size 1.27 1.27)
					(thickness 0.15)
				)
			)
		)
		(property "Author" "Antmicro"
			(at 155.2 216.8 0)
			(layer "B.Fab")
			(hide yes)
			(effects
				(font
					(size 1 1)
					(thickness 0.15)
				)
				(justify mirror)
			)
		)
		(property "License" "Apache-2.0"
			(at 155.2 216.8 0)
			(layer "B.Fab")
			(hide yes)
			(effects
				(font
					(size 1 1)
					(thickness 0.15)
				)
				(justify mirror)
			)
		)
		(property "MPN" "CR0402-FX-1001GLF"
			(at 155.2 216.8 0)
			(layer "B.Fab")
			(hide yes)
			(effects
				(font
					(size 1 1)
					(thickness 0.15)
				)
				(justify mirror)
			)
		)
		(property "Manufacturer" "Bourns"
			(at 155.2 216.8 0)
			(layer "B.Fab")
			(hide yes)
			(effects
				(font
					(size 1 1)
					(thickness 0.15)
				)
				(justify mirror)
			)
		)
		(property "Tolerance" "1%"
			(at 155.2 216.8 0)
			(layer "B.Fab")
			(hide yes)
			(effects
				(font
					(size 1 1)
					(thickness 0.15)
				)
				(justify mirror)
			)
		)
		(property "Val" "1k"
			(at 155.2 216.8 0)
			(layer "B.Fab")
			(hide yes)
			(effects
				(font
					(size 1 1)
					(thickness 0.15)
				)
				(justify mirror)
			)
		)
		(sheetname "USB Debug, DP")
		(sheetfile "usb.kicad_sch")
		(attr smd)
		(fp_rect
			(start -0.925 0.47)
			(end 0.925 -0.47)
			(stroke
				(width 0.05)
				(type default)
			)
			(fill none)
			(layer "B.CrtYd")
		)
		(fp_rect
			(start -0.5 0.25)
			(end 0.5 -0.25)
			(stroke
				(width 0.15)
				(type solid)
			)
			(fill none)
			(layer "B.Fab")
		)
		(fp_text user "${REFERENCE}"
			(at -0.95 -3.168 0)
			(layer "B.Fab")
			(hide yes)
			(effects
				(font
					(size 0.7 0.7)
					(thickness 0.15)
				)
				(justify left bottom mirror)
			)
		)
		(fp_text user "Author: Antmicro"
			(at -0.95 -4.169 0)
			(layer "B.Fab")
			(hide yes)
			(effects
				(font
					(size 0.7 0.7)
					(thickness 0.15)
				)
				(justify left bottom mirror)
			)
		)
		(fp_text user "License: Apache-2.0"
			(at -0.95 -5.169 0)
			(layer "B.Fab")
			(hide yes)
			(effects
				(font
					(size 0.7 0.7)
					(thickness 0.15)
				)
				(justify left bottom mirror)
			)
		)
		(pad "1" smd roundrect
			(at -0.48 0 180)
			(size 0.59 0.64)
			(layers "B.Cu" "B.Paste" "B.Mask")
			(roundrect_rratio 0.25)
			(net 308 "/USB Debug, DP/USBC0_DPEQ1")
			(pintype "passive")
		)
		(pad "2" smd roundrect
			(at 0.48 0 180)
			(size 0.59 0.64)
			(layers "B.Cu" "B.Paste" "B.Mask")
			(roundrect_rratio 0.25)
			(net 1 "GND")
			(pintype "passive")
		)
	)
	(footprint "antmicro-footprints:R_0402_1005Metric"
		(layer "B.Cu")
		(at 43.77 125.35 90)
		(descr "Resistor SMD 0402")
		(tags "resistor SMD 0402")
		(property "Reference" "R73"
			(at -1.2 -1.77 -90)
			(layer "B.SilkS")
			(effects
				(font
					(size 0.7 0.7)
					(thickness 0.15)
				)
				(justify left bottom mirror)
			)
		)
		(property "Value" "R_200R_0402"
			(at 0 -1.4 -90)
			(layer "B.Fab")
			(effects
				(font
					(size 0.7 0.7)
					(thickness 0.15)
				)
				(justify left bottom mirror)
			)
		)
		(property "Footprint" "antmicro-footprints:R_0402_1005Metric"
			(at 0 0 90)
			(layer "F.Fab")
			(hide yes)
			(effects
				(font
					(size 1.27 1.27)
					(thickness 0.15)
				)
			)
		)
		(property "Datasheet" "https://www.bourns.com/docs/product-datasheets/cr.pdf"
			(at 0 0 90)
			(layer "F.Fab")
			(hide yes)
			(effects
				(font
					(size 1.27 1.27)
					(thickness 0.15)
				)
			)
		)
		(property "Author" "Antmicro"
			(at 169.12 81.58 0)
			(layer "B.Fab")
			(hide yes)
			(effects
				(font
					(size 1 1)
					(thickness 0.15)
				)
				(justify mirror)
			)
		)
		(property "License" "Apache-2.0"
			(at 169.12 81.58 0)
			(layer "B.Fab")
			(hide yes)
			(effects
				(font
					(size 1 1)
					(thickness 0.15)
				)
				(justify mirror)
			)
		)
		(property "MPN" "CR0402-FX-2000GLF"
			(at 169.12 81.58 0)
			(layer "B.Fab")
			(hide yes)
			(effects
				(font
					(size 1 1)
					(thickness 0.15)
				)
				(justify mirror)
			)
		)
		(property "Manufacturer" "Bourns"
			(at 169.12 81.58 0)
			(layer "B.Fab")
			(hide yes)
			(effects
				(font
					(size 1 1)
					(thickness 0.15)
				)
				(justify mirror)
			)
		)
		(property "Tolerance" "1%"
			(at 169.12 81.58 0)
			(layer "B.Fab")
			(hide yes)
			(effects
				(font
					(size 1 1)
					(thickness 0.15)
				)
				(justify mirror)
			)
		)
		(property "Val" "200R"
			(at 169.12 81.58 0)
			(layer "B.Fab")
			(hide yes)
			(effects
				(font
					(size 1 1)
					(thickness 0.15)
				)
				(justify mirror)
			)
		)
		(sheetname "USB Debug, DP")
		(sheetfile "usb.kicad_sch")
		(attr smd)
		(fp_rect
			(start -0.925 0.47)
			(end 0.925 -0.47)
			(stroke
				(width 0.05)
				(type default)
			)
			(fill none)
			(layer "B.CrtYd")
		)
		(fp_rect
			(start -0.5 0.25)
			(end 0.5 -0.25)
			(stroke
				(width 0.15)
				(type solid)
			)
			(fill none)
			(layer "B.Fab")
		)
		(fp_text user "${REFERENCE}"
			(at -0.95 -3.168 -90)
			(layer "B.Fab")
			(hide yes)
			(effects
				(font
					(size 0.7 0.7)
					(thickness 0.15)
				)
				(justify left bottom mirror)
			)
		)
		(fp_text user "License: Apache-2.0"
			(at -0.95 -5.169 -90)
			(layer "B.Fab")
			(hide yes)
			(effects
				(font
					(size 0.7 0.7)
					(thickness 0.15)
				)
				(justify left bottom mirror)
			)
		)
		(fp_text user "Author: Antmicro"
			(at -0.95 -4.169 -90)
			(layer "B.Fab")
			(hide yes)
			(effects
				(font
					(size 0.7 0.7)
					(thickness 0.15)
				)
				(justify left bottom mirror)
			)
		)
		(pad "1" smd roundrect
			(at -0.48 0 90)
			(size 0.59 0.64)
			(layers "B.Cu" "B.Paste" "B.Mask")
			(roundrect_rratio 0.25)
			(net 143 "Net-(D3-A)")
			(pintype "passive")
		)
		(pad "2" smd roundrect
			(at 0.48 0 90)
			(size 0.59 0.64)
			(layers "B.Cu" "B.Paste" "B.Mask")
			(roundrect_rratio 0.25)
			(net 185 "/USB Debug, DP/FTDI_3V3")
			(pintype "passive")
		)
	)
	(footprint "antmicro-footprints:R_0402_1005Metric"
		(layer "B.Cu")
		(at 79.5 108.4)
		(descr "Resistor SMD 0402")
		(tags "resistor SMD 0402")
		(property "Reference" "R93"
			(at 3.3 2.34 180)
			(layer "B.SilkS")
			(effects
				(font
					(size 0.7 0.7)
					(thickness 0.15)
				)
				(justify left bottom mirror)
			)
		)
		(property "Value" "R_1k_0402"
			(at 0 -1.4 180)
			(layer "B.Fab")
			(effects
				(font
					(size 0.7 0.7)
					(thickness 0.15)
				)
				(justify left bottom mirror)
			)
		)
		(property "Footprint" "antmicro-footprints:R_0402_1005Metric"
			(at 0 0 0)
			(layer "F.Fab")
			(hide yes)
			(effects
				(font
					(size 1.27 1.27)
					(thickness 0.15)
				)
			)
		)
		(property "Datasheet" "https://www.bourns.com/docs/product-datasheets/cr.pdf"
			(at 0 0 0)
			(layer "F.Fab")
			(hide yes)
			(effects
				(font
					(size 1.27 1.27)
					(thickness 0.15)
				)
			)
		)
		(property "Author" "Antmicro"
			(at 0 0 0)
			(layer "B.Fab")
			(hide yes)
			(effects
				(font
					(size 1 1)
					(thickness 0.15)
				)
				(justify mirror)
			)
		)
		(property "License" "Apache-2.0"
			(at 0 0 0)
			(layer "B.Fab")
			(hide yes)
			(effects
				(font
					(size 1 1)
					(thickness 0.15)
				)
				(justify mirror)
			)
		)
		(property "MPN" "CR0402-FX-1001GLF"
			(at 0 0 0)
			(layer "B.Fab")
			(hide yes)
			(effects
				(font
					(size 1 1)
					(thickness 0.15)
				)
				(justify mirror)
			)
		)
		(property "Manufacturer" "Bourns"
			(at 0 0 0)
			(layer "B.Fab")
			(hide yes)
			(effects
				(font
					(size 1 1)
					(thickness 0.15)
				)
				(justify mirror)
			)
		)
		(property "Tolerance" "1%"
			(at 0 0 0)
			(layer "B.Fab")
			(hide yes)
			(effects
				(font
					(size 1 1)
					(thickness 0.15)
				)
				(justify mirror)
			)
		)
		(property "Val" "1k"
			(at 0 0 0)
			(layer "B.Fab")
			(hide yes)
			(effects
				(font
					(size 1 1)
					(thickness 0.15)
				)
				(justify mirror)
			)
		)
		(sheetname "USB Debug, DP")
		(sheetfile "usb.kicad_sch")
		(attr smd exclude_from_pos_files exclude_from_bom dnp)
		(fp_rect
			(start -0.925 0.47)
			(end 0.925 -0.47)
			(stroke
				(width 0.05)
				(type default)
			)
			(fill none)
			(layer "B.CrtYd")
		)
		(fp_rect
			(start -0.5 0.25)
			(end 0.5 -0.25)
			(stroke
				(width 0.15)
				(type solid)
			)
			(fill none)
			(layer "B.Fab")
		)
		(fp_text user "License: Apache-2.0"
			(at -0.95 -5.169 180)
			(layer "B.Fab")
			(hide yes)
			(effects
				(font
					(size 0.7 0.7)
					(thickness 0.15)
				)
				(justify left bottom mirror)
			)
		)
		(fp_text user "Author: Antmicro"
			(at -0.95 -4.169 180)
			(layer "B.Fab")
			(hide yes)
			(effects
				(font
					(size 0.7 0.7)
					(thickness 0.15)
				)
				(justify left bottom mirror)
			)
		)
		(fp_text user "${REFERENCE}"
			(at -0.95 -3.168 180)
			(layer "B.Fab")
			(hide yes)
			(effects
				(font
					(size 0.7 0.7)
					(thickness 0.15)
				)
				(justify left bottom mirror)
			)
		)
		(pad "1" smd roundrect
			(at -0.48 0)
			(size 0.59 0.64)
			(layers "B.Cu" "B.Paste" "B.Mask")
			(roundrect_rratio 0.25)
			(net 308 "/USB Debug, DP/USBC0_DPEQ1")
			(pintype "passive")
		)
		(pad "2" smd roundrect
			(at 0.48 0)
			(size 0.59 0.64)
			(layers "B.Cu" "B.Paste" "B.Mask")
			(roundrect_rratio 0.25)
			(net 87 "+3V3")
			(pintype "passive")
		)
	)
	(footprint "antmicro-footprints:C_0402_1005Metric"
		(layer "B.Cu")
		(at 126.735 83.75)
		(descr "Capacitor SMD 0402")
		(tags "capacitor SMD 0402")
		(property "Reference" "C13"
			(at 2.965 0.45 180)
			(layer "B.SilkS")
			(effects
				(font
					(size 0.7 0.7)
					(thickness 0.15)
				)
				(justify left bottom mirror)
			)
		)
		(property "Value" "C_220n_0402"
			(at 0 -1.4 180)
			(layer "B.Fab")
			(effects
				(font
					(size 0.7 0.7)
					(thickness 0.15)
				)
				(justify left bottom mirror)
			)
		)
		(property "Footprint" "antmicro-footprints:C_0402_1005Metric"
			(at 0 0 0)
			(layer "F.Fab")
			(hide yes)
			(effects
				(font
					(size 1.27 1.27)
					(thickness 0.15)
				)
			)
		)
		(property "Datasheet" "https://www.yageo.com/en/Chart/Download/pdf/CC0402KRX5R6BB224"
			(at 0 0 0)
			(layer "F.Fab")
			(hide yes)
			(effects
				(font
					(size 1.27 1.27)
					(thickness 0.15)
				)
			)
		)
		(property "Author" "Antmicro"
			(at 0 0 0)
			(layer "B.Fab")
			(hide yes)
			(effects
				(font
					(size 1 1)
					(thickness 0.15)
				)
				(justify mirror)
			)
		)
		(property "Dielectric" ""
			(at 0 0 0)
			(layer "B.Fab")
			(hide yes)
			(effects
				(font
					(size 1 1)
					(thickness 0.15)
				)
				(justify mirror)
			)
		)
		(property "License" "Apache-2.0"
			(at 0 0 0)
			(layer "B.Fab")
			(hide yes)
			(effects
				(font
					(size 1 1)
					(thickness 0.15)
				)
				(justify mirror)
			)
		)
		(property "MPN" "CC0402KRX5R6BB224"
			(at 0 0 0)
			(layer "B.Fab")
			(hide yes)
			(effects
				(font
					(size 1 1)
					(thickness 0.15)
				)
				(justify mirror)
			)
		)
		(property "Manufacturer" "YAGEO"
			(at 0 0 0)
			(layer "B.Fab")
			(hide yes)
			(effects
				(font
					(size 1 1)
					(thickness 0.15)
				)
				(justify mirror)
			)
		)
		(property "Val" "220n"
			(at 0 0 0)
			(layer "B.Fab")
			(hide yes)
			(effects
				(font
					(size 1 1)
					(thickness 0.15)
				)
				(justify mirror)
			)
		)
		(property "Voltage" ""
			(at 0 0 0)
			(layer "B.Fab")
			(hide yes)
			(effects
				(font
					(size 1 1)
					(thickness 0.15)
				)
				(justify mirror)
			)
		)
		(sheetname "M.2")
		(sheetfile "m-2.kicad_sch")
		(attr smd)
		(fp_rect
			(start -0.925 0.47)
			(end 0.925 -0.47)
			(stroke
				(width 0.05)
				(type default)
			)
			(fill none)
			(layer "B.CrtYd")
		)
		(fp_line
			(start -0.494 -0.248)
			(end 0.504 -0.248)
			(stroke
				(width 0.15)
				(type solid)
			)
			(layer "B.Fab")
		)
		(fp_line
			(start -0.494 0.25)
			(end -0.494 -0.248)
			(stroke
				(width 0.15)
				(type solid)
			)
			(layer "B.Fab")
		)
		(fp_line
			(start 0.504 -0.248)
			(end 0.504 0.25)
			(stroke
				(width 0.15)
				(type solid)
			)
			(layer "B.Fab")
		)
		(fp_line
			(start 0.504 0.25)
			(end -0.494 0.25)
			(stroke
				(width 0.15)
				(type solid)
			)
			(layer "B.Fab")
		)
		(fp_text user "Author: Antmicro"
			(at -0.932 -4.17 180)
			(layer "B.Fab")
			(hide yes)
			(effects
				(font
					(size 0.7 0.7)
					(thickness 0.15)
				)
				(justify left bottom mirror)
			)
		)
		(fp_text user "${REFERENCE}"
			(at -0.932 -3.168 180)
			(layer "B.Fab")
			(hide yes)
			(effects
				(font
					(size 0.7 0.7)
					(thickness 0.15)
				)
				(justify left bottom mirror)
			)
		)
		(fp_text user "License: Apache-2.0"
			(at -0.932 -5.17 180)
			(layer "B.Fab")
			(hide yes)
			(effects
				(font
					(size 0.7 0.7)
					(thickness 0.15)
				)
				(justify left bottom mirror)
			)
		)
		(pad "1" smd roundrect
			(at -0.48 0)
			(size 0.59 0.64)
			(layers "B.Cu" "B.Paste" "B.Mask")
			(roundrect_rratio 0.25)
			(net 88 "/M.2/C_PCIE0_TX0_P")
			(pintype "passive")
		)
		(pad "2" smd roundrect
			(at 0.48 0)
			(size 0.59 0.64)
			(layers "B.Cu" "B.Paste" "B.Mask")
			(roundrect_rratio 0.25)
			(net 442 "PCIE0_TX0_P")
			(pintype "passive")
		)
	)
)
